(kicad_pcb
	(version 20260206)
	(generator "pcbnew")
	(generator_version "10.0")
	(general
		(thickness 1.6)
		(legacy_teardrops no)
	)
	(paper "A4")
	(title_block
		(title "peb — Lightning_PEB_BRD.brd")
		(comment 1 "Lightning (Wiwynn / Facebook NVMe JBOF) / footprint 1445 of 2563 (U1), pads 354-468 of 1311")
	)
	(layers
		(0 "F.Cu" signal "TOP")
		(4 "In1.Cu" signal "L2GND")
		(6 "In2.Cu" signal "L3")
		(8 "In3.Cu" signal "L4VCC")
		(10 "In4.Cu" signal "L5VCC")
		(12 "In5.Cu" signal "L6")
		(14 "In6.Cu" signal "L7GND")
		(2 "B.Cu" signal "BOTTOM")
		(9 "F.Adhes" user "F.Adhesive")
		(11 "B.Adhes" user "B.Adhesive")
		(13 "F.Paste" user "Package Geometry/Pastemask Top")
		(15 "B.Paste" user "Package Geometry/Pastemask Bottom")
		(5 "F.SilkS" user "Ref Des/Silkscreen Top")
		(7 "B.SilkS" user "Ref Des/Silkscreen Bottom")
		(1 "F.Mask" user "Board Geometry/Soldermask Top")
		(3 "B.Mask" user "Board Geometry/Soldermask Bottom")
		(17 "Dwgs.User" user "User.Drawings")
		(19 "Cmts.User" user "User.Comments")
		(21 "Eco1.User" user "User.Eco1")
		(23 "Eco2.User" user "User.Eco2")
		(25 "Edge.Cuts" user "Board Geometry/Outline")
		(27 "Margin" user)
		(31 "F.CrtYd" user "Package Geometry/Place Bound Top")
		(29 "B.CrtYd" user "Package Geometry/Place Bound Bottom")
		(35 "F.Fab" user "Ref Des/Assembly Top")
		(33 "B.Fab" user "Ref Des/Assembly Bottom")
	)
	(footprint ""
		(layer "F.Cu")
		(at 240.599976 -47.999904 -90)
		(property "Reference" "U1"
			(at 0 0 270)
			(layer "F.SilkS")
			(hide yes)
			(effects
				(font
					(size 1.27 1.27)
				)
			)
		)
		(property "Value" "PM8546A-FEIP-GP"
			(at -25.785064 -6.40334 270)
			(unlocked yes)
			(layer "F.Fab")
			(hide yes)
			(effects
				(font
					(size 1.016 1.016)
					(thickness 0.1524)
				)
			)
		)
		(property "Device Type" "BGA1311C37D5H134"
			(at -25.785064 -7.92734 270)
			(unlocked yes)
			(layer "F.Fab")
			(hide yes)
			(effects
				(font
					(size 1.016 1.016)
					(thickness 0.1524)
				)
			)
		)
		(duplicate_pad_numbers_are_jumpers no)
		(pad "AK6" smd circle
			(at -12.999974 10.999978 270)
			(size 0.4572 0.4572)
			(layers "F.Cu" "F.Mask" "F.Paste")
			(net "GND")
		)
		(pad "AK7" smd circle
			(at -11.999976 10.999978 270)
			(size 0.4572 0.4572)
			(layers "F.Cu" "F.Mask" "F.Paste")
			(net "DUT_AVD_PCIE")
		)
		(pad "AK8" smd circle
			(at -10.999978 10.999978 270)
			(size 0.4572 0.4572)
			(layers "F.Cu" "F.Mask" "F.Paste")
			(net "GND")
		)
		(pad "AK9" smd circle
			(at -9.99998 10.999978 270)
			(size 0.4572 0.4572)
			(layers "F.Cu" "F.Mask" "F.Paste")
			(net "GND")
		)
		(pad "AK10" smd circle
			(at -8.999982 10.999978 270)
			(size 0.4572 0.4572)
			(layers "F.Cu" "F.Mask" "F.Paste")
			(net "GND")
		)
		(pad "AK11" smd circle
			(at -7.999984 10.999978 270)
			(size 0.4572 0.4572)
			(layers "F.Cu" "F.Mask" "F.Paste")
			(net "GND")
		)
		(pad "AK12" smd circle
			(at -6.999986 10.999978 270)
			(size 0.4572 0.4572)
			(layers "F.Cu" "F.Mask" "F.Paste")
			(net "GND")
		)
		(pad "AK13" smd circle
			(at -5.999988 10.999978 270)
			(size 0.4572 0.4572)
			(layers "F.Cu" "F.Mask" "F.Paste")
			(net "GND")
		)
		(pad "AK14" smd circle
			(at -4.99999 10.999978 270)
			(size 0.4572 0.4572)
			(layers "F.Cu" "F.Mask" "F.Paste")
			(net "GND")
		)
		(pad "AK15" smd circle
			(at -3.999992 10.999978 270)
			(size 0.4572 0.4572)
			(layers "F.Cu" "F.Mask" "F.Paste")
			(net "GND")
		)
		(pad "AK16" smd circle
			(at -2.999994 10.999978 270)
			(size 0.4572 0.4572)
			(layers "F.Cu" "F.Mask" "F.Paste")
			(net "GND")
		)
		(pad "AK17" smd circle
			(at -1.999996 10.999978 270)
			(size 0.4572 0.4572)
			(layers "F.Cu" "F.Mask" "F.Paste")
			(net "GND")
		)
		(pad "AK18" smd circle
			(at -0.999998 10.999978 270)
			(size 0.4572 0.4572)
			(layers "F.Cu" "F.Mask" "F.Paste")
			(net "GND")
		)
		(pad "AK19" smd circle
			(at 0 10.999978 270)
			(size 0.4572 0.4572)
			(layers "F.Cu" "F.Mask" "F.Paste")
			(net "GND")
		)
		(pad "AK20" smd circle
			(at 0.999998 10.999978 270)
			(size 0.4572 0.4572)
			(layers "F.Cu" "F.Mask" "F.Paste")
			(net "DUT_AVD_PCIE")
		)
		(pad "AK21" smd circle
			(at 1.999996 10.999978 270)
			(size 0.4572 0.4572)
			(layers "F.Cu" "F.Mask" "F.Paste")
			(net "GND")
		)
		(pad "AK22" smd circle
			(at 2.999994 10.999978 270)
			(size 0.4572 0.4572)
			(layers "F.Cu" "F.Mask" "F.Paste")
			(net "GND")
		)
		(pad "AK23" smd circle
			(at 3.999992 10.999978 270)
			(size 0.4572 0.4572)
			(layers "F.Cu" "F.Mask" "F.Paste")
			(net "GND")
		)
		(pad "AK24" smd circle
			(at 4.99999 10.999978 270)
			(size 0.4572 0.4572)
			(layers "F.Cu" "F.Mask" "F.Paste")
			(net "GND")
		)
		(pad "AK25" smd circle
			(at 5.999988 10.999978 270)
			(size 0.4572 0.4572)
			(layers "F.Cu" "F.Mask" "F.Paste")
			(net "DUT_AVD_PCIE")
		)
		(pad "AK26" smd circle
			(at 6.999986 10.999978 270)
			(size 0.4572 0.4572)
			(layers "F.Cu" "F.Mask" "F.Paste")
			(net "GND")
		)
		(pad "AK27" smd circle
			(at 7.999984 10.999978 270)
			(size 0.4572 0.4572)
			(layers "F.Cu" "F.Mask" "F.Paste")
			(net "LBI_DATA_8")
		)
		(pad "AK28" smd circle
			(at 8.999982 10.999978 270)
			(size 0.4572 0.4572)
			(layers "F.Cu" "F.Mask" "F.Paste")
			(net "LBI_DATA_9")
		)
		(pad "AK29" smd circle
			(at 9.99998 10.999978 270)
			(size 0.4572 0.4572)
			(layers "F.Cu" "F.Mask" "F.Paste")
			(net "LBI_DATA10")
		)
		(pad "AK30" smd circle
			(at 10.999978 10.999978 270)
			(size 0.4572 0.4572)
			(layers "F.Cu" "F.Mask" "F.Paste")
			(net "LBI_DATA11_R")
		)
		(pad "AK31" smd circle
			(at 11.999976 10.999978 270)
			(size 0.4572 0.4572)
			(layers "F.Cu" "F.Mask" "F.Paste")
			(net "LBI_DATA12_R")
		)
		(pad "AK32" smd circle
			(at 12.999974 10.999978 270)
			(size 0.4572 0.4572)
			(layers "F.Cu" "F.Mask" "F.Paste")
			(net "LBI_DATA13_R")
		)
		(pad "AK33" smd circle
			(at 13.999972 10.999978 270)
			(size 0.4572 0.4572)
			(layers "F.Cu" "F.Mask" "F.Paste")
			(net "LBI_DATA14_R")
		)
		(pad "AK34" smd circle
			(at 14.99997 10.999978 270)
			(size 0.4572 0.4572)
			(layers "F.Cu" "F.Mask" "F.Paste")
			(net "GND")
		)
		(pad "AK35" smd circle
			(at 15.999968 10.999978 270)
			(size 0.4572 0.4572)
			(layers "F.Cu" "F.Mask" "F.Paste")
			(net "GND")
		)
		(pad "AK36" smd circle
			(at 16.999966 10.999978 270)
			(size 0.4572 0.4572)
			(layers "F.Cu" "F.Mask" "F.Paste")
			(net "PCIE_TX_CAP_P95")
		)
		(pad "AK37" smd circle
			(at 17.999964 10.999978 270)
			(size 0.4572 0.4572)
			(layers "F.Cu" "F.Mask" "F.Paste")
			(net "PCIE_TX_CAP_N95")
		)
		(pad "AL2" smd circle
			(at -16.999966 11.999976 270)
			(size 0.4572 0.4572)
			(layers "F.Cu" "F.Mask" "F.Paste")
			(net "PCIE_TX_CAP_N58")
		)
		(pad "AL3" smd circle
			(at -15.999968 11.999976 270)
			(size 0.4572 0.4572)
			(layers "F.Cu" "F.Mask" "F.Paste")
			(net "PCIE_TX_CAP_P58")
		)
		(pad "AL4" smd circle
			(at -14.99997 11.999976 270)
			(size 0.4572 0.4572)
			(layers "F.Cu" "F.Mask" "F.Paste")
			(net "GND")
		)
		(pad "AL5" smd circle
			(at -13.999972 11.999976 270)
			(size 0.4572 0.4572)
			(layers "F.Cu" "F.Mask" "F.Paste")
			(net "PCIE_RX_N58")
		)
		(pad "AL6" smd circle
			(at -12.999974 11.999976 270)
			(size 0.4572 0.4572)
			(layers "F.Cu" "F.Mask" "F.Paste")
			(net "PCIE_RX_P58")
		)
		(pad "AL7" smd circle
			(at -11.999976 11.999976 270)
			(size 0.4572 0.4572)
			(layers "F.Cu" "F.Mask" "F.Paste")
			(net "DUT_AVD_PCIE")
		)
		(pad "AL8" smd circle
			(at -10.999978 11.999976 270)
			(size 0.4572 0.4572)
			(layers "F.Cu" "F.Mask" "F.Paste")
			(net "DUT_AVD_PCIE")
		)
		(pad "AL9" smd circle
			(at -9.99998 11.999976 270)
			(size 0.4572 0.4572)
			(layers "F.Cu" "F.Mask" "F.Paste")
			(net "DUT_AVD_PCIE")
		)
		(pad "AL10" smd circle
			(at -8.999982 11.999976 270)
			(size 0.4572 0.4572)
			(layers "F.Cu" "F.Mask" "F.Paste")
			(net "DUT_AVD_PCIE")
		)
		(pad "AL11" smd circle
			(at -7.999984 11.999976 270)
			(size 0.4572 0.4572)
			(layers "F.Cu" "F.Mask" "F.Paste")
			(net "DUT_AVD_PCIE")
		)
		(pad "AL12" smd circle
			(at -6.999986 11.999976 270)
			(size 0.4572 0.4572)
			(layers "F.Cu" "F.Mask" "F.Paste")
			(net "DUT_AVD_PCIE")
		)
		(pad "AL13" smd circle
			(at -5.999988 11.999976 270)
			(size 0.4572 0.4572)
			(layers "F.Cu" "F.Mask" "F.Paste")
			(net "DUT_AVD_PCIE")
		)
		(pad "AL14" smd circle
			(at -4.99999 11.999976 270)
			(size 0.4572 0.4572)
			(layers "F.Cu" "F.Mask" "F.Paste")
			(net "DUT_AVD_PCIE")
		)
		(pad "AL15" smd circle
			(at -3.999992 11.999976 270)
			(size 0.4572 0.4572)
			(layers "F.Cu" "F.Mask" "F.Paste")
			(net "GND")
		)
		(pad "AL16" smd circle
			(at -2.999994 11.999976 270)
			(size 0.4572 0.4572)
			(layers "F.Cu" "F.Mask" "F.Paste")
			(net "DUT_AVD_PCIE")
		)
		(pad "AL17" smd circle
			(at -1.999996 11.999976 270)
			(size 0.4572 0.4572)
			(layers "F.Cu" "F.Mask" "F.Paste")
			(net "DUT_AVD_PCIE")
		)
		(pad "AL18" smd circle
			(at -0.999998 11.999976 270)
			(size 0.4572 0.4572)
			(layers "F.Cu" "F.Mask" "F.Paste")
			(net "DUT_AVD_PCIE")
		)
		(pad "AL19" smd circle
			(at 0 11.999976 270)
			(size 0.4572 0.4572)
			(layers "F.Cu" "F.Mask" "F.Paste")
			(net "DUT_AVD_PCIE")
		)
		(pad "AL20" smd circle
			(at 0.999998 11.999976 270)
			(size 0.4572 0.4572)
			(layers "F.Cu" "F.Mask" "F.Paste")
			(net "DUT_AVD_PCIE")
		)
		(pad "AL21" smd circle
			(at 1.999996 11.999976 270)
			(size 0.4572 0.4572)
			(layers "F.Cu" "F.Mask" "F.Paste")
			(net "DUT_AVD_PCIE")
		)
		(pad "AL22" smd circle
			(at 2.999994 11.999976 270)
			(size 0.4572 0.4572)
			(layers "F.Cu" "F.Mask" "F.Paste")
			(net "DUT_AVD_PCIE")
		)
		(pad "AL23" smd circle
			(at 3.999992 11.999976 270)
			(size 0.4572 0.4572)
			(layers "F.Cu" "F.Mask" "F.Paste")
			(net "DUT_AVD_PCIE")
		)
		(pad "AL24" smd circle
			(at 4.99999 11.999976 270)
			(size 0.4572 0.4572)
			(layers "F.Cu" "F.Mask" "F.Paste")
			(net "DUT_AVD_PCIE")
		)
		(pad "AL25" smd circle
			(at 5.999988 11.999976 270)
			(size 0.4572 0.4572)
			(layers "F.Cu" "F.Mask" "F.Paste")
			(net "DUT_AVD_PCIE")
		)
		(pad "AL26" smd circle
			(at 6.999986 11.999976 270)
			(size 0.4572 0.4572)
			(layers "F.Cu" "F.Mask" "F.Paste")
			(net "DUT_AVD_PCIE")
		)
		(pad "AL27" smd circle
			(at 7.999984 11.999976 270)
			(size 0.4572 0.4572)
			(layers "F.Cu" "F.Mask" "F.Paste")
			(net "DUT_AVD_PCIE")
		)
		(pad "AL28" smd circle
			(at 8.999982 11.999976 270)
			(size 0.4572 0.4572)
			(layers "F.Cu" "F.Mask" "F.Paste")
			(net "DUT_AVD_PCIE")
		)
		(pad "AL29" smd circle
			(at 9.99998 11.999976 270)
			(size 0.4572 0.4572)
			(layers "F.Cu" "F.Mask" "F.Paste")
			(net "DUT_AVD_PCIE")
		)
		(pad "AL30" smd circle
			(at 10.999978 11.999976 270)
			(size 0.4572 0.4572)
			(layers "F.Cu" "F.Mask" "F.Paste")
			(net "DUT_AVD_PCIE")
		)
		(pad "AL31" smd circle
			(at 11.999976 11.999976 270)
			(size 0.4572 0.4572)
			(layers "F.Cu" "F.Mask" "F.Paste")
			(net "DUT_AVD_PCIE")
		)
		(pad "AL32" smd circle
			(at 12.999974 11.999976 270)
			(size 0.4572 0.4572)
			(layers "F.Cu" "F.Mask" "F.Paste")
			(net "DUT_AVD_PCIE")
		)
		(pad "AL33" smd circle
			(at 13.999972 11.999976 270)
			(size 0.4572 0.4572)
			(layers "F.Cu" "F.Mask" "F.Paste")
			(net "DUT_AVD_PCIE")
		)
		(pad "AL34" smd circle
			(at 14.99997 11.999976 270)
			(size 0.4572 0.4572)
			(layers "F.Cu" "F.Mask" "F.Paste")
			(net "GND")
		)
		(pad "AL35" smd circle
			(at 15.999968 11.999976 270)
			(size 0.4572 0.4572)
			(layers "F.Cu" "F.Mask" "F.Paste")
			(net "PCIE_TX_CAP_P94")
		)
		(pad "AL36" smd circle
			(at 16.999966 11.999976 270)
			(size 0.4572 0.4572)
			(layers "F.Cu" "F.Mask" "F.Paste")
			(net "PCIE_TX_CAP_N94")
		)
		(pad "AM1" smd circle
			(at -17.999964 12.999974 270)
			(size 0.4572 0.4572)
			(layers "F.Cu" "F.Mask" "F.Paste")
			(net "PCIE_TX_CAP_N59")
		)
		(pad "AM2" smd circle
			(at -16.999966 12.999974 270)
			(size 0.4572 0.4572)
			(layers "F.Cu" "F.Mask" "F.Paste")
			(net "PCIE_TX_CAP_P59")
		)
		(pad "AM3" smd circle
			(at -15.999968 12.999974 270)
			(size 0.4572 0.4572)
			(layers "F.Cu" "F.Mask" "F.Paste")
			(net "GND")
		)
		(pad "AM4" smd circle
			(at -14.99997 12.999974 270)
			(size 0.4572 0.4572)
			(layers "F.Cu" "F.Mask" "F.Paste")
			(net "PCIE_RX_N59")
		)
		(pad "AM5" smd circle
			(at -13.999972 12.999974 270)
			(size 0.4572 0.4572)
			(layers "F.Cu" "F.Mask" "F.Paste")
			(net "PCIE_RX_P59")
		)
		(pad "AM6" smd circle
			(at -12.999974 12.999974 270)
			(size 0.4572 0.4572)
			(layers "F.Cu" "F.Mask" "F.Paste")
			(net "GND")
		)
		(pad "AM7" smd circle
			(at -11.999976 12.999974 270)
			(size 0.4572 0.4572)
			(layers "F.Cu" "F.Mask" "F.Paste")
			(net "DUT_AVD_PCIE")
		)
		(pad "AM8" smd circle
			(at -10.999978 12.999974 270)
			(size 0.4572 0.4572)
			(layers "F.Cu" "F.Mask" "F.Paste")
			(net "PCIE_RX_P64")
		)
		(pad "AM9" smd circle
			(at -9.99998 12.999974 270)
			(size 0.4572 0.4572)
			(layers "F.Cu" "F.Mask" "F.Paste")
			(net "GND")
		)
		(pad "AM10" smd circle
			(at -8.999982 12.999974 270)
			(size 0.4572 0.4572)
			(layers "F.Cu" "F.Mask" "F.Paste")
			(net "PCIE_RX_P66")
		)
		(pad "AM11" smd circle
			(at -7.999984 12.999974 270)
			(size 0.4572 0.4572)
			(layers "F.Cu" "F.Mask" "F.Paste")
			(net "GND")
		)
		(pad "AM12" smd circle
			(at -6.999986 12.999974 270)
			(size 0.4572 0.4572)
			(layers "F.Cu" "F.Mask" "F.Paste")
			(net "PCIE_RX_P68")
		)
		(pad "AM13" smd circle
			(at -5.999988 12.999974 270)
			(size 0.4572 0.4572)
			(layers "F.Cu" "F.Mask" "F.Paste")
			(net "GND")
		)
		(pad "AM14" smd circle
			(at -4.99999 12.999974 270)
			(size 0.4572 0.4572)
			(layers "F.Cu" "F.Mask" "F.Paste")
			(net "PCIE_RX_P70")
		)
		(pad "AM15" smd circle
			(at -3.999992 12.999974 270)
			(size 0.4572 0.4572)
			(layers "F.Cu" "F.Mask" "F.Paste")
			(net "GND")
		)
		(pad "AM16" smd circle
			(at -2.999994 12.999974 270)
			(size 0.4572 0.4572)
			(layers "F.Cu" "F.Mask" "F.Paste")
			(net "DUT_AVD_PCIE")
		)
		(pad "AM17" smd circle
			(at -1.999996 12.999974 270)
			(size 0.4572 0.4572)
			(layers "F.Cu" "F.Mask" "F.Paste")
			(net "PCIE_RX_P72")
		)
		(pad "AM18" smd circle
			(at -0.999998 12.999974 270)
			(size 0.4572 0.4572)
			(layers "F.Cu" "F.Mask" "F.Paste")
			(net "GND")
		)
		(pad "AM19" smd circle
			(at 0 12.999974 270)
			(size 0.4572 0.4572)
			(layers "F.Cu" "F.Mask" "F.Paste")
			(net "PCIE_RX_P74")
		)
		(pad "AM20" smd circle
			(at 0.999998 12.999974 270)
			(size 0.4572 0.4572)
			(layers "F.Cu" "F.Mask" "F.Paste")
			(net "GND")
		)
		(pad "AM21" smd circle
			(at 1.999996 12.999974 270)
			(size 0.4572 0.4572)
			(layers "F.Cu" "F.Mask" "F.Paste")
			(net "PCIE_RX_P76")
		)
		(pad "AM22" smd circle
			(at 2.999994 12.999974 270)
			(size 0.4572 0.4572)
			(layers "F.Cu" "F.Mask" "F.Paste")
			(net "GND")
		)
		(pad "AM23" smd circle
			(at 3.999992 12.999974 270)
			(size 0.4572 0.4572)
			(layers "F.Cu" "F.Mask" "F.Paste")
			(net "PCIE_RX_P78")
		)
		(pad "AM24" smd circle
			(at 4.99999 12.999974 270)
			(size 0.4572 0.4572)
			(layers "F.Cu" "F.Mask" "F.Paste")
			(net "GND")
		)
		(pad "AM25" smd circle
			(at 5.999988 12.999974 270)
			(size 0.4572 0.4572)
			(layers "F.Cu" "F.Mask" "F.Paste")
			(net "DUT_AVD_PCIE")
		)
		(pad "AM26" smd circle
			(at 6.999986 12.999974 270)
			(size 0.4572 0.4572)
			(layers "F.Cu" "F.Mask" "F.Paste")
			(net "PCIE_RX_P80")
		)
		(pad "AM27" smd circle
			(at 7.999984 12.999974 270)
			(size 0.4572 0.4572)
			(layers "F.Cu" "F.Mask" "F.Paste")
			(net "GND")
		)
		(pad "AM28" smd circle
			(at 8.999982 12.999974 270)
			(size 0.4572 0.4572)
			(layers "F.Cu" "F.Mask" "F.Paste")
			(net "PCIE_RX_P82")
		)
		(pad "AM29" smd circle
			(at 9.99998 12.999974 270)
			(size 0.4572 0.4572)
			(layers "F.Cu" "F.Mask" "F.Paste")
			(net "GND")
		)
		(pad "AM30" smd circle
			(at 10.999978 12.999974 270)
			(size 0.4572 0.4572)
			(layers "F.Cu" "F.Mask" "F.Paste")
			(net "PCIE_RX_P84")
		)
		(pad "AM31" smd circle
			(at 11.999976 12.999974 270)
			(size 0.4572 0.4572)
			(layers "F.Cu" "F.Mask" "F.Paste")
			(net "GND")
		)
		(pad "AM32" smd circle
			(at 12.999974 12.999974 270)
			(size 0.4572 0.4572)
			(layers "F.Cu" "F.Mask" "F.Paste")
			(net "PCIE_RX_P86")
		)
		(pad "AM33" smd circle
			(at 13.999972 12.999974 270)
			(size 0.4572 0.4572)
			(layers "F.Cu" "F.Mask" "F.Paste")
			(net "DUT_AVD_PCIE")
		)
		(pad "AM34" smd circle
			(at 14.99997 12.999974 270)
			(size 0.4572 0.4572)
			(layers "F.Cu" "F.Mask" "F.Paste")
			(net "GND")
		)
		(pad "AM35" smd circle
			(at 15.999968 12.999974 270)
			(size 0.4572 0.4572)
			(layers "F.Cu" "F.Mask" "F.Paste")
			(net "GND")
		)
		(pad "AM36" smd circle
			(at 16.999966 12.999974 270)
			(size 0.4572 0.4572)
			(layers "F.Cu" "F.Mask" "F.Paste")
			(net "PCIE_TX_CAP_P93")
		)
		(pad "AM37" smd circle
			(at 17.999964 12.999974 270)
			(size 0.4572 0.4572)
			(layers "F.Cu" "F.Mask" "F.Paste")
			(net "PCIE_TX_CAP_N93")
		)
		(pad "AN2" smd circle
			(at -16.999966 13.999972 270)
			(size 0.4572 0.4572)
			(layers "F.Cu" "F.Mask" "F.Paste")
			(net "PCIE_TX_CAP_N60")
		)
		(pad "AN3" smd circle
			(at -15.999968 13.999972 270)
			(size 0.4572 0.4572)
			(layers "F.Cu" "F.Mask" "F.Paste")
			(net "PCIE_TX_CAP_P60")
		)
		(pad "AN4" smd circle
			(at -14.99997 13.999972 270)
			(size 0.4572 0.4572)
			(layers "F.Cu" "F.Mask" "F.Paste")
			(net "GND")
		)
		(pad "AN5" smd circle
			(at -13.999972 13.999972 270)
			(size 0.4572 0.4572)
			(layers "F.Cu" "F.Mask" "F.Paste")
			(net "PCIE_RX_N60")
		)
		(pad "AN6" smd circle
			(at -12.999974 13.999972 270)
			(size 0.4572 0.4572)
			(layers "F.Cu" "F.Mask" "F.Paste")
			(net "PCIE_RX_P60")
		)
		(pad "AN7" smd circle
			(at -11.999976 13.999972 270)
			(size 0.4572 0.4572)
			(layers "F.Cu" "F.Mask" "F.Paste")
			(net "GND")
		)
		(pad "AN8" smd circle
			(at -10.999978 13.999972 270)
			(size 0.4572 0.4572)
			(layers "F.Cu" "F.Mask" "F.Paste")
			(net "PCIE_RX_N64")
		)
		(pad "AN9" smd circle
			(at -9.99998 13.999972 270)
			(size 0.4572 0.4572)
			(layers "F.Cu" "F.Mask" "F.Paste")
			(net "PCIE_RX_P65")
		)
		(pad "AN10" smd circle
			(at -8.999982 13.999972 270)
			(size 0.4572 0.4572)
			(layers "F.Cu" "F.Mask" "F.Paste")
			(net "PCIE_RX_N66")
		)
		(pad "AN11" smd circle
			(at -7.999984 13.999972 270)
			(size 0.4572 0.4572)
			(layers "F.Cu" "F.Mask" "F.Paste")
			(net "PCIE_RX_P67")
		)
		(pad "AN12" smd circle
			(at -6.999986 13.999972 270)
			(size 0.4572 0.4572)
			(layers "F.Cu" "F.Mask" "F.Paste")
			(net "PCIE_RX_N68")
		)
	)
)
